(kicad_pcb
	(version 20260206)
	(generator "pcbnew")
	(generator_version "10.0")
	(general
		(thickness 1.6)
		(legacy_teardrops no)
	)
	(paper "A4")
	(title_block
		(title "fcb — Lightning_FCB_BRD.brd")
		(comment 1 "Lightning (Wiwynn / Facebook NVMe JBOF) / footprints 181-187 of 495")
	)
	(layers
		(0 "F.Cu" signal "TOP")
		(4 "In1.Cu" signal "L2GND")
		(6 "In2.Cu" signal "L3VCC")
		(2 "B.Cu" signal "BOTTOM")
		(9 "F.Adhes" user "F.Adhesive")
		(11 "B.Adhes" user "B.Adhesive")
		(13 "F.Paste" user "Package Geometry/Pastemask Top")
		(15 "B.Paste" user "Package Geometry/Pastemask Bottom")
		(5 "F.SilkS" user "Ref Des/Silkscreen Top")
		(7 "B.SilkS" user "Ref Des/Silkscreen Bottom")
		(1 "F.Mask" user "Board Geometry/Soldermask Top")
		(3 "B.Mask" user "Board Geometry/Soldermask Bottom")
		(17 "Dwgs.User" user "User.Drawings")
		(19 "Cmts.User" user "User.Comments")
		(21 "Eco1.User" user "User.Eco1")
		(23 "Eco2.User" user "User.Eco2")
		(25 "Edge.Cuts" user "Board Geometry/Outline")
		(27 "Margin" user)
		(31 "F.CrtYd" user "Package Geometry/Place Bound Top")
		(29 "B.CrtYd" user "Package Geometry/Place Bound Bottom")
		(35 "F.Fab" user "Ref Des/Assembly Top")
		(33 "B.Fab" user "Ref Des/Assembly Bottom")
	)
	(footprint ""
		(layer "F.Cu")
		(at 27.9654 -355.5238 90)
		(property "Reference" "Q10"
			(at 0 0 90)
			(layer "F.SilkS")
			(hide yes)
			(effects
				(font
					(size 1.27 1.27)
				)
			)
		)
		(property "Value" "2N7002DW-7F-GP"
			(at -2.3622 -8.2042 90)
			(unlocked yes)
			(layer "F.Fab")
			(hide yes)
			(effects
				(font
					(size 1.016 1.016)
					(thickness 0.1524)
				)
			)
		)
		(property "Device Type" "SOT-363H44"
			(at -2.3622 -10.1092 90)
			(unlocked yes)
			(layer "F.Fab")
			(hide yes)
			(effects
				(font
					(size 1.016 1.016)
					(thickness 0.1524)
				)
			)
		)
		(duplicate_pad_numbers_are_jumpers no)
		(fp_line
			(start 1.4478 -1.7018)
			(end -1.4478 -1.7018)
			(stroke
				(width 0.1524)
				(type default)
			)
			(layer "F.SilkS")
		)
		(fp_line
			(start -1.4478 -1.7018)
			(end -1.4478 1.7018)
			(stroke
				(width 0.1524)
				(type default)
			)
			(layer "F.SilkS")
		)
		(fp_line
			(start -1.27 1.524)
			(end -1.27 0.6604)
			(stroke
				(width 0.4826)
				(type default)
			)
			(layer "F.SilkS")
		)
		(fp_line
			(start 1.4478 1.7018)
			(end 1.4478 -1.7018)
			(stroke
				(width 0.1524)
				(type default)
			)
			(layer "F.SilkS")
		)
		(fp_line
			(start -1.4478 1.7018)
			(end 1.4478 1.7018)
			(stroke
				(width 0.1524)
				(type default)
			)
			(layer "F.SilkS")
		)
		(fp_poly
			(pts
				(xy -1.524 -1.778) (xy 1.524 -1.778) (xy 1.524 1.778) (xy -1.524 1.778)
			)
			(stroke
				(width 0)
				(type default)
			)
			(fill no)
			(layer "F.CrtYd")
		)
		(fp_poly
			(pts
				(xy -1.524 -1.778) (xy 1.524 -1.778) (xy 1.524 1.778) (xy -1.524 1.778)
			)
			(stroke
				(width 0)
				(type default)
			)
			(fill no)
			(layer "F.Fab")
		)
		(pad "1" smd rect
			(at -0.65024 0.9398 90)
			(size 0.4064 1.016)
			(layers "F.Cu" "F.Mask" "F.Paste")
			(net "GND")
		)
		(pad "2" smd rect
			(at 0 0.9398 90)
			(size 0.4064 1.016)
			(layers "F.Cu" "F.Mask" "F.Paste")
			(net "TEMP_ALM#")
		)
		(pad "3" smd rect
			(at 0.65024 0.9398 90)
			(size 0.4064 1.016)
			(layers "F.Cu" "F.Mask" "F.Paste")
			(net "TEMP_ALM#_JP_2")
		)
		(pad "4" smd rect
			(at 0.65024 -0.9398 90)
			(size 0.4064 1.016)
			(layers "F.Cu" "F.Mask" "F.Paste")
			(net "GND")
		)
		(pad "5" smd rect
			(at 0 -0.9398 90)
			(size 0.4064 1.016)
			(layers "F.Cu" "F.Mask" "F.Paste")
			(net "TEMP_ALM#_G")
		)
		(pad "6" smd rect
			(at -0.65024 -0.9398 90)
			(size 0.4064 1.016)
			(layers "F.Cu" "F.Mask" "F.Paste")
			(net "TEMP_ALM#_G")
		)
	)
	(footprint ""
		(layer "F.Cu")
		(at 32.766 -374.777 180)
		(property "Reference" "PR10"
			(at 0 0 180)
			(layer "F.SilkS")
			(hide yes)
			(effects
				(font
					(size 1.27 1.27)
				)
			)
		)
		(property "Value" "0R0402-PAD-2-GP"
			(at 0 -2.8702 180)
			(unlocked yes)
			(layer "F.Fab")
			(hide yes)
			(effects
				(font
					(size 1.016 1.016)
					(thickness 0.1524)
				)
			)
		)
		(property "Device Type" "0R0402-PAD-1"
			(at 0 -4.3942 180)
			(unlocked yes)
			(layer "F.Fab")
			(hide yes)
			(effects
				(font
					(size 1.016 1.016)
					(thickness 0.1524)
				)
			)
		)
		(duplicate_pad_numbers_are_jumpers no)
		(fp_line
			(start 0.508 -0.9398)
			(end -0.508 -0.9398)
			(stroke
				(width 0.1524)
				(type default)
			)
			(layer "F.SilkS")
		)
		(fp_line
			(start -0.508 -0.9398)
			(end -0.508 0.9398)
			(stroke
				(width 0.1524)
				(type default)
			)
			(layer "F.SilkS")
		)
		(fp_rect
			(start -0.508 0.9398)
			(end 0.508 -0.9398)
			(stroke
				(width 0)
				(type default)
			)
			(fill no)
			(layer "F.CrtYd")
		)
		(fp_rect
			(start -0.508 0.9398)
			(end 0.508 -0.9398)
			(stroke
				(width 0)
				(type default)
			)
			(fill no)
			(layer "F.Fab")
		)
		(pad "1" smd custom
			(at 0 -0.4445 180)
			(size 0.1397 0.1397)
			(layers "F.Cu" "F.Mask" "F.Paste")
			(net "ADM1276_GATE_DRV")
			(options
				(clearance outline)
				(anchor circle)
			)
			(primitives
				(gr_poly
					(pts
						(xy -0.2794 0.3683)
						(arc
							(start -0.2794 -0.2667)
							(mid -0.249642 -0.338542)
							(end -0.1778 -0.3683)
						)
						(arc
							(start 0.1778 -0.3683)
							(mid 0.249642 -0.338542)
							(end 0.2794 -0.2667)
						)
						(xy 0.2794 0.3683)
					)
					(width 0)
					(fill yes)
				)
			)
		)
		(pad "2" smd custom
			(at 0 0.4445 180)
			(size 0.1397 0.1397)
			(layers "F.Cu" "F.Mask" "F.Paste")
			(net "ADM1276_GATE")
			(options
				(clearance outline)
				(anchor circle)
			)
			(primitives
				(gr_poly
					(pts
						(arc
							(start -0.1778 0.3683)
							(mid -0.249642 0.338542)
							(end -0.2794 0.2667)
						)
						(xy -0.2794 -0.3683) (xy 0.2794 -0.3683)
						(arc
							(start 0.2794 0.2667)
							(mid 0.249642 0.338542)
							(end 0.1778 0.3683)
						)
					)
					(width 0)
					(fill yes)
				)
			)
		)
	)
	(footprint ""
		(layer "F.Cu")
		(at 35.541966 -153.45791 90)
		(property "Reference" "TP13"
			(at 0 0 90)
			(layer "F.SilkS")
			(hide yes)
			(effects
				(font
					(size 1.27 1.27)
				)
			)
		)
		(property "Value" "TPAD32-GP"
			(at 0 -3.166364 90)
			(unlocked yes)
			(layer "F.Fab")
			(hide yes)
			(effects
				(font
					(size 1.016 1.016)
					(thickness 0.1524)
				)
			)
		)
		(property "Device Type" "TPAD32"
			(at 0 -4.690618 90)
			(unlocked yes)
			(layer "F.Fab")
			(hide yes)
			(effects
				(font
					(size 1.016 1.016)
					(thickness 0.1524)
				)
			)
		)
		(duplicate_pad_numbers_are_jumpers no)
		(fp_poly
			(pts
				(arc
					(start 0.7112 0)
					(mid -0.7112 0)
					(end 0.7112 0)
				)
			)
			(stroke
				(width 0)
				(type default)
			)
			(fill no)
			(layer "F.CrtYd")
		)
		(fp_poly
			(pts
				(arc
					(start 0.7112 0)
					(mid -0.7112 0)
					(end 0.7112 0)
				)
			)
			(stroke
				(width 0)
				(type default)
			)
			(fill no)
			(layer "F.Fab")
		)
		(pad "1" smd circle
			(at 0 0 90)
			(size 0.8128 0.8128)
			(layers "F.Cu" "F.Mask" "F.Paste")
			(net "NCT7904_VSEN13")
		)
	)
	(footprint ""
		(layer "F.Cu")
		(at 19.2278 -182.1942)
		(property "Reference" "C36"
			(at 0 0 0)
			(layer "F.SilkS")
			(hide yes)
			(effects
				(font
					(size 1.27 1.27)
				)
			)
		)
		(property "Value" "SCD1U16V2KX-3GP"
			(at 1.1811 -2.7051 0)
			(unlocked yes)
			(layer "F.Fab")
			(hide yes)
			(effects
				(font
					(size 1.016 1.016)
					(thickness 0.1524)
				)
			)
		)
		(property "Device Type" "C402H22"
			(at 1.1811 -4.2291 0)
			(unlocked yes)
			(layer "F.Fab")
			(hide yes)
			(effects
				(font
					(size 1.016 1.016)
					(thickness 0.1524)
				)
			)
		)
		(duplicate_pad_numbers_are_jumpers no)
		(fp_rect
			(start -0.4318 0.9525)
			(end 0.4318 -0.9525)
			(stroke
				(width 0)
				(type default)
			)
			(fill no)
			(layer "F.CrtYd")
		)
		(fp_rect
			(start -0.4318 0.9525)
			(end 0.4318 -0.9525)
			(stroke
				(width 0)
				(type default)
			)
			(fill no)
			(layer "F.Fab")
		)
		(pad "1" smd custom
			(at 0 -0.4445)
			(size 0.1524 0.1524)
			(layers "F.Cu" "F.Mask" "F.Paste")
			(net "FAN_TACH7")
			(options
				(clearance outline)
				(anchor circle)
			)
			(primitives
				(gr_poly
					(pts
						(arc
							(start 0.3048 -0.2032)
							(mid 0.275042 -0.275042)
							(end 0.2032 -0.3048)
						)
						(arc
							(start -0.2032 -0.3048)
							(mid -0.275042 -0.275042)
							(end -0.3048 -0.2032)
						)
						(arc
							(start -0.3048 0.2032)
							(mid -0.275042 0.275042)
							(end -0.2032 0.3048)
						)
						(arc
							(start 0.2032 0.3048)
							(mid 0.275042 0.275042)
							(end 0.3048 0.2032)
						)
					)
					(width 0)
					(fill yes)
				)
			)
		)
		(pad "2" smd custom
			(at 0 0.4445)
			(size 0.1524 0.1524)
			(layers "F.Cu" "F.Mask" "F.Paste")
			(net "GND")
			(options
				(clearance outline)
				(anchor circle)
			)
			(primitives
				(gr_poly
					(pts
						(arc
							(start 0.3048 -0.2032)
							(mid 0.275042 -0.275042)
							(end 0.2032 -0.3048)
						)
						(arc
							(start -0.2032 -0.3048)
							(mid -0.275042 -0.275042)
							(end -0.3048 -0.2032)
						)
						(arc
							(start -0.3048 0.2032)
							(mid -0.275042 0.275042)
							(end -0.2032 0.3048)
						)
						(arc
							(start 0.2032 0.3048)
							(mid 0.275042 0.275042)
							(end 0.3048 0.2032)
						)
					)
					(width 0)
					(fill yes)
				)
			)
		)
	)
	(footprint ""
		(layer "F.Cu")
		(at 17.8816 -255.0922 -90)
		(property "Reference" "R82"
			(at 0 0 270)
			(layer "F.SilkS")
			(hide yes)
			(effects
				(font
					(size 1.27 1.27)
				)
			)
		)
		(property "Value" "4K7R2F-GP"
			(at 0.064008 -3.993896 270)
			(unlocked yes)
			(layer "F.Fab")
			(hide yes)
			(effects
				(font
					(size 1.016 1.016)
					(thickness 0.1524)
				)
			)
		)
		(property "Device Type" "R402H16"
			(at 0.064008 -5.517896 270)
			(unlocked yes)
			(layer "F.Fab")
			(hide yes)
			(effects
				(font
					(size 1.016 1.016)
					(thickness 0.1524)
				)
			)
		)
		(duplicate_pad_numbers_are_jumpers no)
		(fp_line
			(start -0.508 -0.9398)
			(end -0.508 0.9398)
			(stroke
				(width 0.1524)
				(type default)
			)
			(layer "F.SilkS")
		)
		(fp_line
			(start 0.508 -0.9398)
			(end -0.508 -0.9398)
			(stroke
				(width 0.1524)
				(type default)
			)
			(layer "F.SilkS")
		)
		(fp_rect
			(start -0.508 0.9398)
			(end 0.508 -0.9398)
			(stroke
				(width 0)
				(type default)
			)
			(fill no)
			(layer "F.CrtYd")
		)
		(fp_rect
			(start -0.508 0.9398)
			(end 0.508 -0.9398)
			(stroke
				(width 0)
				(type default)
			)
			(fill no)
			(layer "F.Fab")
		)
		(pad "1" smd custom
			(at 0 -0.4445 270)
			(size 0.1397 0.1397)
			(layers "F.Cu" "F.Mask" "F.Paste")
			(net "P12V")
			(options
				(clearance outline)
				(anchor circle)
			)
			(primitives
				(gr_poly
					(pts
						(arc
							(start -0.1778 -0.2794)
							(mid -0.249642 -0.249642)
							(end -0.2794 -0.1778)
						)
						(arc
							(start -0.2794 0.1778)
							(mid -0.249642 0.249642)
							(end -0.1778 0.2794)
						)
						(arc
							(start 0.1778 0.2794)
							(mid 0.249642 0.249642)
							(end 0.2794 0.1778)
						)
						(arc
							(start 0.2794 -0.1778)
							(mid 0.249642 -0.249642)
							(end 0.1778 -0.2794)
						)
					)
					(width 0)
					(fill yes)
				)
			)
		)
		(pad "2" smd custom
			(at 0 0.4445 270)
			(size 0.1397 0.1397)
			(layers "F.Cu" "F.Mask" "F.Paste")
			(net "FAN_TACH5")
			(options
				(clearance outline)
				(anchor circle)
			)
			(primitives
				(gr_poly
					(pts
						(arc
							(start -0.1778 -0.2794)
							(mid -0.249642 -0.249642)
							(end -0.2794 -0.1778)
						)
						(arc
							(start -0.2794 0.1778)
							(mid -0.249642 0.249642)
							(end -0.1778 0.2794)
						)
						(arc
							(start 0.1778 0.2794)
							(mid 0.249642 0.249642)
							(end 0.2794 0.1778)
						)
						(arc
							(start 0.2794 -0.1778)
							(mid 0.249642 -0.249642)
							(end 0.1778 -0.2794)
						)
					)
					(width 0)
					(fill yes)
				)
			)
		)
	)
	(footprint ""
		(layer "F.Cu")
		(at 18.796 -260.4516 -90)
		(property "Reference" "R80"
			(at 0 0 270)
			(layer "F.SilkS")
			(hide yes)
			(effects
				(font
					(size 1.27 1.27)
				)
			)
		)
		(property "Value" "4K7R2F-GP"
			(at 0.064008 -3.993896 270)
			(unlocked yes)
			(layer "F.Fab")
			(hide yes)
			(effects
				(font
					(size 1.016 1.016)
					(thickness 0.1524)
				)
			)
		)
		(property "Device Type" "R402H16"
			(at 0.064008 -5.517896 270)
			(unlocked yes)
			(layer "F.Fab")
			(hide yes)
			(effects
				(font
					(size 1.016 1.016)
					(thickness 0.1524)
				)
			)
		)
		(duplicate_pad_numbers_are_jumpers no)
		(fp_line
			(start -0.508 -0.9398)
			(end -0.508 0.9398)
			(stroke
				(width 0.1524)
				(type default)
			)
			(layer "F.SilkS")
		)
		(fp_line
			(start 0.508 -0.9398)
			(end -0.508 -0.9398)
			(stroke
				(width 0.1524)
				(type default)
			)
			(layer "F.SilkS")
		)
		(fp_rect
			(start -0.508 0.9398)
			(end 0.508 -0.9398)
			(stroke
				(width 0)
				(type default)
			)
			(fill no)
			(layer "F.CrtYd")
		)
		(fp_rect
			(start -0.508 0.9398)
			(end 0.508 -0.9398)
			(stroke
				(width 0)
				(type default)
			)
			(fill no)
			(layer "F.Fab")
		)
		(pad "1" smd custom
			(at 0 -0.4445 270)
			(size 0.1397 0.1397)
			(layers "F.Cu" "F.Mask" "F.Paste")
			(net "P12V")
			(options
				(clearance outline)
				(anchor circle)
			)
			(primitives
				(gr_poly
					(pts
						(arc
							(start -0.1778 -0.2794)
							(mid -0.249642 -0.249642)
							(end -0.2794 -0.1778)
						)
						(arc
							(start -0.2794 0.1778)
							(mid -0.249642 0.249642)
							(end -0.1778 0.2794)
						)
						(arc
							(start 0.1778 0.2794)
							(mid 0.249642 0.249642)
							(end 0.2794 0.1778)
						)
						(arc
							(start 0.2794 -0.1778)
							(mid 0.249642 -0.249642)
							(end 0.1778 -0.2794)
						)
					)
					(width 0)
					(fill yes)
				)
			)
		)
		(pad "2" smd custom
			(at 0 0.4445 270)
			(size 0.1397 0.1397)
			(layers "F.Cu" "F.Mask" "F.Paste")
			(net "FAN_TACH6")
			(options
				(clearance outline)
				(anchor circle)
			)
			(primitives
				(gr_poly
					(pts
						(arc
							(start -0.1778 -0.2794)
							(mid -0.249642 -0.249642)
							(end -0.2794 -0.1778)
						)
						(arc
							(start -0.2794 0.1778)
							(mid -0.249642 0.249642)
							(end -0.1778 0.2794)
						)
						(arc
							(start 0.1778 0.2794)
							(mid 0.249642 0.249642)
							(end 0.2794 0.1778)
						)
						(arc
							(start 0.2794 -0.1778)
							(mid 0.249642 -0.249642)
							(end 0.1778 -0.2794)
						)
					)
					(width 0)
					(fill yes)
				)
			)
		)
	)
	(footprint ""
		(layer "F.Cu")
		(at 7.949946 -56.099964 -90)
		(property "Reference" "LED6"
			(at 0 0 270)
			(layer "F.SilkS")
			(hide yes)
			(effects
				(font
					(size 1.27 1.27)
				)
			)
		)
		(property "Value" "LED-RB-6-GP"
			(at -4.6736 3.8354 270)
			(unlocked yes)
			(layer "F.Fab")
			(hide yes)
			(effects
				(font
					(size 1.016 1.016)
					(thickness 0.1524)
				)
			)
		)
		(property "Device Type" "LED-100-3P-067106H325"
			(at -4.6736 2.3114 270)
			(unlocked yes)
			(layer "F.Fab")
			(hide yes)
			(effects
				(font
					(size 1.016 1.016)
					(thickness 0.1524)
				)
			)
		)
		(duplicate_pad_numbers_are_jumpers no)
		(fp_line
			(start -1.7526 10.414)
			(end -1.7526 6.6548)
			(stroke
				(width 0.1524)
				(type default)
			)
			(layer "F.SilkS")
		)
		(fp_line
			(start 1.7526 10.414)
			(end -1.7526 10.414)
			(stroke
				(width 0.1524)
				(type default)
			)
			(layer "F.SilkS")
		)
		(fp_line
			(start -3.6068 6.6548)
			(end -3.6068 -0.889)
			(stroke
				(width 0.1524)
				(type default)
			)
			(layer "F.SilkS")
		)
		(fp_line
			(start -1.7526 6.6548)
			(end -3.6068 6.6548)
			(stroke
				(width 0.1524)
				(type default)
			)
			(layer "F.SilkS")
		)
		(fp_line
			(start 1.7526 6.6548)
			(end 1.7526 10.414)
			(stroke
				(width 0.1524)
				(type default)
			)
			(layer "F.SilkS")
		)
		(fp_line
			(start 3.6068 6.6548)
			(end 1.7526 6.6548)
			(stroke
				(width 0.1524)
				(type default)
			)
			(layer "F.SilkS")
		)
		(fp_line
			(start -3.6068 -0.889)
			(end 3.6068 -0.889)
			(stroke
				(width 0.1524)
				(type default)
			)
			(layer "F.SilkS")
		)
		(fp_line
			(start 3.6068 -0.889)
			(end 3.6068 6.6548)
			(stroke
				(width 0.1524)
				(type default)
			)
			(layer "F.SilkS")
		)
		(fp_circle
			(center -2.54 0)
			(end -2.54 -0.9906)
			(stroke
				(width 0.3048)
				(type default)
			)
			(fill no)
			(layer "F.SilkS")
		)
		(fp_circle
			(center 0 0)
			(end 0 -0.9906)
			(stroke
				(width 0.3048)
				(type default)
			)
			(fill no)
			(layer "F.SilkS")
		)
		(fp_circle
			(center 2.54 0)
			(end 2.54 -0.9906)
			(stroke
				(width 0.3048)
				(type default)
			)
			(fill no)
			(layer "F.SilkS")
		)
		(fp_poly
			(pts
				(xy -1.4986 10.1473) (xy -1.4986 6.4008) (xy -3.3528 6.4008) (xy -3.3528 -0.3937) (xy 3.3528 -0.3937)
				(xy 3.3528 6.4008) (xy 1.4986 6.4008) (xy 1.4986 10.1473)
			)
			(stroke
				(width 0)
				(type default)
			)
			(fill no)
			(layer "F.CrtYd")
		)
		(fp_poly
			(pts
				(xy -2.0066 10.668) (xy 2.0066 10.668) (xy 2.0066 6.9088) (xy 3.8608 6.9088) (xy 3.8608 2.2098)
				(xy 3.3528 2.2098) (xy 3.3528 6.4008) (xy 1.4986 6.4008) (xy 1.4986 10.1473) (xy -1.4986 10.1473)
				(xy -1.4986 6.4008) (xy -3.3528 6.4008) (xy -3.3528 -0.3937) (xy 3.3528 -0.3937) (xy 3.3528 2.1971)
				(xy 3.8608 2.1971) (xy 3.8608 -1.143) (xy -3.8608 -1.143) (xy -3.8608 6.9088) (xy -2.0066 6.9088)
			)
			(stroke
				(width 0)
				(type default)
			)
			(fill no)
			(layer "F.CrtYd")
		)
		(fp_poly
			(pts
				(xy -2.0066 10.668) (xy -2.0066 6.9088) (xy -3.8608 6.9088) (xy -3.8608 -1.143) (xy 3.8608 -1.143)
				(xy 3.8608 6.9088) (xy 2.0066 6.9088) (xy 2.0066 10.668)
			)
			(stroke
				(width 0)
				(type default)
			)
			(fill no)
			(layer "F.Fab")
		)
		(pad "1" thru_hole circle
			(at 2.54 0 270)
			(size 1.27 1.27)
			(drill 0.889)
			(layers "*.Cu" "*.Mask")
			(remove_unused_layers no)
			(net "LED_DR_LED5_BLUE")
			(clearance 0.1651)
			(thermal_gap 0.1651)
		)
		(pad "2" thru_hole circle
			(at 0 0 270)
			(size 1.27 1.27)
			(drill 0.889)
			(layers "*.Cu" "*.Mask")
			(remove_unused_layers no)
			(net "LED_DR_LED5_K")
			(clearance 0.1651)
			(thermal_gap 0.1651)
		)
		(pad "3" thru_hole circle
			(at -2.54 0 270)
			(size 1.27 1.27)
			(drill 0.889)
			(layers "*.Cu" "*.Mask")
			(remove_unused_layers no)
			(net "LED_DR_LED5")
			(clearance 0.1651)
			(thermal_gap 0.1651)
		)
	)
)
